(kicad_pcb
	(version 20260206)
	(generator "pcbnew")
	(generator_version "10.0")
	(general
		(thickness 1.6)
		(legacy_teardrops no)
	)
	(paper "A4")
	(title_block
		(title "Bryce Canyon_F.DPB_16315-1-OCP.brd")
		(comment 1 "Bryce Canyon / footprints 836-843 of 2223")
	)
	(layers
		(0 "F.Cu" signal "TOP")
		(4 "In1.Cu" signal "L2GND")
		(6 "In2.Cu" signal "L3")
		(8 "In3.Cu" signal "L4GND")
		(10 "In4.Cu" signal "L5")
		(12 "In5.Cu" signal "L6VCC")
		(14 "In6.Cu" signal "L7VCC")
		(16 "In7.Cu" signal "L8")
		(18 "In8.Cu" signal "L9GND")
		(20 "In9.Cu" signal "L10")
		(22 "In10.Cu" signal "L11GND")
		(2 "B.Cu" signal "BOTTOM")
		(9 "F.Adhes" user "F.Adhesive")
		(11 "B.Adhes" user "B.Adhesive")
		(13 "F.Paste" user "Package Geometry/Pastemask Top")
		(15 "B.Paste" user "Package Geometry/Pastemask Bottom")
		(5 "F.SilkS" user "Ref Des/Silkscreen Top")
		(7 "B.SilkS" user "Ref Des/Silkscreen Bottom")
		(1 "F.Mask" user "Board Geometry/Soldermask Top")
		(3 "B.Mask" user "Board Geometry/Soldermask Bottom")
		(17 "Dwgs.User" user "User.Drawings")
		(19 "Cmts.User" user "User.Comments")
		(21 "Eco1.User" user "User.Eco1")
		(23 "Eco2.User" user "User.Eco2")
		(25 "Edge.Cuts" user "Board Geometry/Outline")
		(27 "Margin" user)
		(31 "F.CrtYd" user "Package Geometry/Place Bound Top")
		(29 "B.CrtYd" user "Package Geometry/Place Bound Bottom")
		(35 "F.Fab" user "Ref Des/Assembly Top")
		(33 "B.Fab" user "Ref Des/Assembly Bottom")
	)
	(footprint ""
		(layer "F.Cu")
		(at 437.75884 -130.34391 -90)
		(property "Reference" "R546"
			(at 0 0 270)
			(layer "F.SilkS")
			(hide yes)
			(effects
				(font
					(size 1.27 1.27)
				)
			)
		)
		(property "Value" "4K7R2J-2-GP"
			(at 0.064008 -3.993896 270)
			(unlocked yes)
			(layer "F.Fab")
			(hide yes)
			(effects
				(font
					(size 1.016 1.016)
					(thickness 0.1524)
				)
			)
		)
		(property "Device Type" "R402H16"
			(at 0.064008 -5.517896 270)
			(unlocked yes)
			(layer "F.Fab")
			(hide yes)
			(effects
				(font
					(size 1.016 1.016)
					(thickness 0.1524)
				)
			)
		)
		(duplicate_pad_numbers_are_jumpers no)
		(fp_line
			(start -0.508 -0.9398)
			(end -0.508 0.9398)
			(stroke
				(width 0.1524)
				(type default)
			)
			(layer "F.SilkS")
		)
		(fp_line
			(start 0.508 -0.9398)
			(end -0.508 -0.9398)
			(stroke
				(width 0.1524)
				(type default)
			)
			(layer "F.SilkS")
		)
		(fp_rect
			(start -0.508 0.9398)
			(end 0.508 -0.9398)
			(stroke
				(width 0)
				(type default)
			)
			(fill no)
			(layer "F.CrtYd")
		)
		(fp_rect
			(start -0.508 0.9398)
			(end 0.508 -0.9398)
			(stroke
				(width 0)
				(type default)
			)
			(fill no)
			(layer "F.Fab")
		)
		(pad "1" smd custom
			(at 0 -0.4445 270)
			(size 0.1397 0.1397)
			(layers "F.Cu" "F.Mask" "F.Paste")
			(net "DRIVE_A_22_FLT_LED")
			(options
				(clearance outline)
				(anchor circle)
			)
			(primitives
				(gr_poly
					(pts
						(arc
							(start -0.1778 -0.2794)
							(mid -0.249642 -0.249642)
							(end -0.2794 -0.1778)
						)
						(arc
							(start -0.2794 0.1778)
							(mid -0.249642 0.249642)
							(end -0.1778 0.2794)
						)
						(arc
							(start 0.1778 0.2794)
							(mid 0.249642 0.249642)
							(end 0.2794 0.1778)
						)
						(arc
							(start 0.2794 -0.1778)
							(mid 0.249642 -0.249642)
							(end 0.1778 -0.2794)
						)
					)
					(width 0)
					(fill yes)
				)
			)
		)
		(pad "2" smd custom
			(at 0 0.4445 270)
			(size 0.1397 0.1397)
			(layers "F.Cu" "F.Mask" "F.Paste")
			(net "GND")
			(options
				(clearance outline)
				(anchor circle)
			)
			(primitives
				(gr_poly
					(pts
						(arc
							(start -0.1778 -0.2794)
							(mid -0.249642 -0.249642)
							(end -0.2794 -0.1778)
						)
						(arc
							(start -0.2794 0.1778)
							(mid -0.249642 0.249642)
							(end -0.1778 0.2794)
						)
						(arc
							(start 0.1778 0.2794)
							(mid 0.249642 0.249642)
							(end 0.2794 0.1778)
						)
						(arc
							(start 0.2794 -0.1778)
							(mid 0.249642 -0.249642)
							(end 0.1778 -0.2794)
						)
					)
					(width 0)
					(fill yes)
				)
			)
		)
	)
	(footprint ""
		(layer "F.Cu")
		(at 164.814504 -301.245778 90)
		(property "Reference" "R572"
			(at 0 0 90)
			(layer "F.SilkS")
			(hide yes)
			(effects
				(font
					(size 1.27 1.27)
				)
			)
		)
		(property "Value" "4K7R2J-2-GP"
			(at 0.064008 -3.993896 90)
			(unlocked yes)
			(layer "F.Fab")
			(hide yes)
			(effects
				(font
					(size 1.016 1.016)
					(thickness 0.1524)
				)
			)
		)
		(property "Device Type" "R402H16"
			(at 0.064008 -5.517896 90)
			(unlocked yes)
			(layer "F.Fab")
			(hide yes)
			(effects
				(font
					(size 1.016 1.016)
					(thickness 0.1524)
				)
			)
		)
		(duplicate_pad_numbers_are_jumpers no)
		(fp_line
			(start 0.508 -0.9398)
			(end -0.508 -0.9398)
			(stroke
				(width 0.1524)
				(type default)
			)
			(layer "F.SilkS")
		)
		(fp_line
			(start -0.508 -0.9398)
			(end -0.508 0.9398)
			(stroke
				(width 0.1524)
				(type default)
			)
			(layer "F.SilkS")
		)
		(fp_rect
			(start -0.508 0.9398)
			(end 0.508 -0.9398)
			(stroke
				(width 0)
				(type default)
			)
			(fill no)
			(layer "F.CrtYd")
		)
		(fp_rect
			(start -0.508 0.9398)
			(end 0.508 -0.9398)
			(stroke
				(width 0)
				(type default)
			)
			(fill no)
			(layer "F.Fab")
		)
		(pad "1" smd custom
			(at 0 -0.4445 90)
			(size 0.1397 0.1397)
			(layers "F.Cu" "F.Mask" "F.Paste")
			(net "DRIVE_B_29_FLT_LED")
			(options
				(clearance outline)
				(anchor circle)
			)
			(primitives
				(gr_poly
					(pts
						(arc
							(start -0.1778 -0.2794)
							(mid -0.249642 -0.249642)
							(end -0.2794 -0.1778)
						)
						(arc
							(start -0.2794 0.1778)
							(mid -0.249642 0.249642)
							(end -0.1778 0.2794)
						)
						(arc
							(start 0.1778 0.2794)
							(mid 0.249642 0.249642)
							(end 0.2794 0.1778)
						)
						(arc
							(start 0.2794 -0.1778)
							(mid 0.249642 -0.249642)
							(end 0.1778 -0.2794)
						)
					)
					(width 0)
					(fill yes)
				)
			)
		)
		(pad "2" smd custom
			(at 0 0.4445 90)
			(size 0.1397 0.1397)
			(layers "F.Cu" "F.Mask" "F.Paste")
			(net "GND")
			(options
				(clearance outline)
				(anchor circle)
			)
			(primitives
				(gr_poly
					(pts
						(arc
							(start -0.1778 -0.2794)
							(mid -0.249642 -0.249642)
							(end -0.2794 -0.1778)
						)
						(arc
							(start -0.2794 0.1778)
							(mid -0.249642 0.249642)
							(end -0.1778 0.2794)
						)
						(arc
							(start 0.1778 0.2794)
							(mid 0.249642 0.249642)
							(end 0.2794 0.1778)
						)
						(arc
							(start 0.2794 -0.1778)
							(mid 0.249642 -0.249642)
							(end 0.1778 -0.2794)
						)
					)
					(width 0)
					(fill yes)
				)
			)
		)
	)
	(footprint ""
		(layer "F.Cu")
		(at 26.051002 -250.37415 -90)
		(property "Reference" "R1219"
			(at 0 0 270)
			(layer "F.SilkS")
			(hide yes)
			(effects
				(font
					(size 1.27 1.27)
				)
			)
		)
		(property "Value" "309KR2F-GP"
			(at 0.064008 -3.993896 270)
			(unlocked yes)
			(layer "F.Fab")
			(hide yes)
			(effects
				(font
					(size 1.016 1.016)
					(thickness 0.1524)
				)
			)
		)
		(property "Device Type" "R402H16"
			(at 0.064008 -5.517896 270)
			(unlocked yes)
			(layer "F.Fab")
			(hide yes)
			(effects
				(font
					(size 1.016 1.016)
					(thickness 0.1524)
				)
			)
		)
		(duplicate_pad_numbers_are_jumpers no)
		(fp_line
			(start -0.508 -0.9398)
			(end -0.508 0.9398)
			(stroke
				(width 0.1524)
				(type default)
			)
			(layer "F.SilkS")
		)
		(fp_line
			(start 0.508 -0.9398)
			(end -0.508 -0.9398)
			(stroke
				(width 0.1524)
				(type default)
			)
			(layer "F.SilkS")
		)
		(fp_rect
			(start -0.508 0.9398)
			(end 0.508 -0.9398)
			(stroke
				(width 0)
				(type default)
			)
			(fill no)
			(layer "F.CrtYd")
		)
		(fp_rect
			(start -0.508 0.9398)
			(end 0.508 -0.9398)
			(stroke
				(width 0)
				(type default)
			)
			(fill no)
			(layer "F.Fab")
		)
		(pad "1" smd custom
			(at 0 -0.4445 270)
			(size 0.1397 0.1397)
			(layers "F.Cu" "F.Mask" "F.Paste")
			(net "P5V_A_RF")
			(options
				(clearance outline)
				(anchor circle)
			)
			(primitives
				(gr_poly
					(pts
						(arc
							(start -0.1778 -0.2794)
							(mid -0.249642 -0.249642)
							(end -0.2794 -0.1778)
						)
						(arc
							(start -0.2794 0.1778)
							(mid -0.249642 0.249642)
							(end -0.1778 0.2794)
						)
						(arc
							(start 0.1778 0.2794)
							(mid 0.249642 0.249642)
							(end 0.2794 0.1778)
						)
						(arc
							(start 0.2794 -0.1778)
							(mid 0.249642 -0.249642)
							(end 0.1778 -0.2794)
						)
					)
					(width 0)
					(fill yes)
				)
			)
		)
		(pad "2" smd custom
			(at 0 0.4445 270)
			(size 0.1397 0.1397)
			(layers "F.Cu" "F.Mask" "F.Paste")
			(net "P5V_A_VREG")
			(options
				(clearance outline)
				(anchor circle)
			)
			(primitives
				(gr_poly
					(pts
						(arc
							(start -0.1778 -0.2794)
							(mid -0.249642 -0.249642)
							(end -0.2794 -0.1778)
						)
						(arc
							(start -0.2794 0.1778)
							(mid -0.249642 0.249642)
							(end -0.1778 0.2794)
						)
						(arc
							(start 0.1778 0.2794)
							(mid 0.249642 0.249642)
							(end 0.2794 0.1778)
						)
						(arc
							(start 0.2794 -0.1778)
							(mid 0.249642 -0.249642)
							(end 0.1778 -0.2794)
						)
					)
					(width 0)
					(fill yes)
				)
			)
		)
	)
	(footprint ""
		(layer "F.Cu")
		(at 252.271276 -248.87936)
		(property "Reference" "R58"
			(at 0 0 0)
			(layer "F.SilkS")
			(hide yes)
			(effects
				(font
					(size 1.27 1.27)
				)
			)
		)
		(property "Value" "0R2J-2-GP"
			(at 0.064008 -3.993896 0)
			(unlocked yes)
			(layer "F.Fab")
			(hide yes)
			(effects
				(font
					(size 1.016 1.016)
					(thickness 0.1524)
				)
			)
		)
		(property "Device Type" "R402H16"
			(at 0.064008 -5.517896 0)
			(unlocked yes)
			(layer "F.Fab")
			(hide yes)
			(effects
				(font
					(size 1.016 1.016)
					(thickness 0.1524)
				)
			)
		)
		(duplicate_pad_numbers_are_jumpers no)
		(fp_line
			(start -0.508 -0.9398)
			(end -0.508 0.9398)
			(stroke
				(width 0.1524)
				(type default)
			)
			(layer "F.SilkS")
		)
		(fp_line
			(start 0.508 -0.9398)
			(end -0.508 -0.9398)
			(stroke
				(width 0.1524)
				(type default)
			)
			(layer "F.SilkS")
		)
		(fp_rect
			(start -0.508 0.9398)
			(end 0.508 -0.9398)
			(stroke
				(width 0)
				(type default)
			)
			(fill no)
			(layer "F.CrtYd")
		)
		(fp_rect
			(start -0.508 0.9398)
			(end 0.508 -0.9398)
			(stroke
				(width 0)
				(type default)
			)
			(fill no)
			(layer "F.Fab")
		)
		(pad "1" smd custom
			(at 0 -0.4445)
			(size 0.1397 0.1397)
			(layers "F.Cu" "F.Mask" "F.Paste")
			(net "IO_EXP6_INT_N")
			(options
				(clearance outline)
				(anchor circle)
			)
			(primitives
				(gr_poly
					(pts
						(arc
							(start -0.1778 -0.2794)
							(mid -0.249642 -0.249642)
							(end -0.2794 -0.1778)
						)
						(arc
							(start -0.2794 0.1778)
							(mid -0.249642 0.249642)
							(end -0.1778 0.2794)
						)
						(arc
							(start 0.1778 0.2794)
							(mid 0.249642 0.249642)
							(end 0.2794 0.1778)
						)
						(arc
							(start 0.2794 -0.1778)
							(mid 0.249642 -0.249642)
							(end 0.1778 -0.2794)
						)
					)
					(width 0)
					(fill yes)
				)
			)
		)
		(pad "2" smd custom
			(at 0 0.4445)
			(size 0.1397 0.1397)
			(layers "F.Cu" "F.Mask" "F.Paste")
			(net "DRIVE_INSERT_ALERT_A_N")
			(options
				(clearance outline)
				(anchor circle)
			)
			(primitives
				(gr_poly
					(pts
						(arc
							(start -0.1778 -0.2794)
							(mid -0.249642 -0.249642)
							(end -0.2794 -0.1778)
						)
						(arc
							(start -0.2794 0.1778)
							(mid -0.249642 0.249642)
							(end -0.1778 0.2794)
						)
						(arc
							(start 0.1778 0.2794)
							(mid 0.249642 0.249642)
							(end 0.2794 0.1778)
						)
						(arc
							(start 0.2794 -0.1778)
							(mid 0.249642 -0.249642)
							(end 0.1778 -0.2794)
						)
					)
					(width 0)
					(fill yes)
				)
			)
		)
	)
	(footprint ""
		(layer "F.Cu")
		(at 479.384614 -274.219416 -90)
		(property "Reference" "C181"
			(at 0 0 270)
			(layer "F.SilkS")
			(hide yes)
			(effects
				(font
					(size 1.27 1.27)
				)
			)
		)
		(property "Value" "SCD01U16V1KX-GP"
			(at -2.8321 -1.7399 270)
			(unlocked yes)
			(layer "F.Fab")
			(hide yes)
			(effects
				(font
					(size 1.016 1.016)
					(thickness 0.1524)
				)
			)
		)
		(property "Device Type" "C0201H13"
			(at -2.8321 -3.2639 270)
			(unlocked yes)
			(layer "F.Fab")
			(hide yes)
			(effects
				(font
					(size 1.016 1.016)
					(thickness 0.1524)
				)
			)
		)
		(duplicate_pad_numbers_are_jumpers no)
		(fp_rect
			(start -0.2794 0.6477)
			(end 0.2794 -0.6477)
			(stroke
				(width 0)
				(type default)
			)
			(fill no)
			(layer "F.CrtYd")
		)
		(fp_rect
			(start -0.2794 0.6477)
			(end 0.2794 -0.6477)
			(stroke
				(width 0)
				(type default)
			)
			(fill no)
			(layer "F.Fab")
		)
		(pad "1" smd custom
			(at 0 -0.2794 270)
			(size 0.0762 0.0762)
			(layers "F.Cu" "F.Mask" "F.Paste")
			(net "SAS_HDD_RX_N11")
			(options
				(clearance outline)
				(anchor circle)
			)
			(primitives
				(gr_poly
					(pts
						(arc
							(start 0.1524 -0.127)
							(mid 0.137521 -0.162921)
							(end 0.1016 -0.1778)
						)
						(arc
							(start -0.1016 -0.1778)
							(mid -0.137521 -0.162921)
							(end -0.1524 -0.127)
						)
						(arc
							(start -0.1524 0.127)
							(mid -0.137521 0.162921)
							(end -0.1016 0.1778)
						)
						(arc
							(start 0.1016 0.1778)
							(mid 0.137521 0.162921)
							(end 0.1524 0.127)
						)
					)
					(width 0)
					(fill yes)
				)
			)
		)
		(pad "2" smd custom
			(at 0 0.2794 270)
			(size 0.0762 0.0762)
			(layers "F.Cu" "F.Mask" "F.Paste")
			(net "PHY_SCC_A_TO_DRV_A_11_DN")
			(options
				(clearance outline)
				(anchor circle)
			)
			(primitives
				(gr_poly
					(pts
						(arc
							(start 0.1524 -0.127)
							(mid 0.137521 -0.162921)
							(end 0.1016 -0.1778)
						)
						(arc
							(start -0.1016 -0.1778)
							(mid -0.137521 -0.162921)
							(end -0.1524 -0.127)
						)
						(arc
							(start -0.1524 0.127)
							(mid -0.137521 0.162921)
							(end -0.1016 0.1778)
						)
						(arc
							(start 0.1016 0.1778)
							(mid 0.137521 0.162921)
							(end 0.1524 0.127)
						)
					)
					(width 0)
					(fill yes)
				)
			)
		)
	)
	(footprint ""
		(layer "F.Cu")
		(at 130.433318 -145.397474)
		(property "Reference" "D42"
			(at 0 0 0)
			(layer "F.SilkS")
			(hide yes)
			(effects
				(font
					(size 1.27 1.27)
				)
			)
		)
		(property "Value" "MMPZ5228BPT-GP"
			(at 0 -6.7818 0)
			(unlocked yes)
			(layer "F.Fab")
			(hide yes)
			(effects
				(font
					(size 1.016 1.016)
					(thickness 0.1524)
				)
			)
		)
		(property "Device Type" "SOD323AKH40"
			(at 0 -8.6868 0)
			(unlocked yes)
			(layer "F.Fab")
			(hide yes)
			(effects
				(font
					(size 1.016 1.016)
					(thickness 0.1524)
				)
			)
		)
		(duplicate_pad_numbers_are_jumpers no)
		(fp_line
			(start -0.889 -1.9304)
			(end 0.889 -1.9304)
			(stroke
				(width 0.1524)
				(type default)
			)
			(layer "F.SilkS")
		)
		(fp_line
			(start -0.889 2.159)
			(end -0.889 -1.9304)
			(stroke
				(width 0.1524)
				(type default)
			)
			(layer "F.SilkS")
		)
		(fp_line
			(start 0.762 2.0574)
			(end -0.762 2.0574)
			(stroke
				(width 0.508)
				(type default)
			)
			(layer "F.SilkS")
		)
		(fp_line
			(start 0.889 -1.9304)
			(end 0.889 2.159)
			(stroke
				(width 0.1524)
				(type default)
			)
			(layer "F.SilkS")
		)
		(fp_line
			(start 0.889 2.159)
			(end -0.889 2.159)
			(stroke
				(width 0.1524)
				(type default)
			)
			(layer "F.SilkS")
		)
		(fp_rect
			(start -1.016 2.3114)
			(end 1.016 -2.0066)
			(stroke
				(width 0)
				(type default)
			)
			(fill no)
			(layer "F.CrtYd")
		)
		(fp_poly
			(pts
				(xy -1.016 -2.0066) (xy 1.016 -2.0066) (xy 1.016 2.3114) (xy -1.016 2.3114)
			)
			(stroke
				(width 0)
				(type default)
			)
			(fill no)
			(layer "F.Fab")
		)
		(pad "A" smd rect
			(at 0 -1.143)
			(size 0.5588 1.016)
			(layers "F.Cu" "F.Mask" "F.Paste")
			(net "GND")
		)
		(pad "K" smd rect
			(at 0 1.143)
			(size 0.5588 1.016)
			(layers "F.Cu" "F.Mask" "F.Paste")
			(net "VCCP_A")
		)
	)
	(footprint ""
		(layer "F.Cu")
		(at 255.389634 -3.617722 90)
		(property "Reference" "TP213"
			(at 0 0 90)
			(layer "F.SilkS")
			(hide yes)
			(effects
				(font
					(size 1.27 1.27)
				)
			)
		)
		(property "Value" "TPAD32-GP"
			(at -0.0508 -1.6764 90)
			(unlocked yes)
			(layer "F.Fab")
			(hide yes)
			(effects
				(font
					(size 1.016 1.016)
					(thickness 0.1524)
				)
			)
		)
		(property "Device Type" "TPAD32"
			(at -0.0508 -3.2004 90)
			(unlocked yes)
			(layer "F.Fab")
			(hide yes)
			(effects
				(font
					(size 1.016 1.016)
					(thickness 0.1524)
				)
			)
		)
		(duplicate_pad_numbers_are_jumpers no)
		(fp_poly
			(pts
				(arc
					(start 0 0.4064)
					(mid 0 -0.4064)
					(end 0 0.4064)
				)
			)
			(stroke
				(width 0)
				(type default)
			)
			(fill no)
			(layer "F.CrtYd")
		)
		(fp_poly
			(pts
				(arc
					(start 0 0.7112)
					(mid 0 -0.7112)
					(end 0 0.7112)
				)
			)
			(stroke
				(width 0)
				(type default)
			)
			(fill no)
			(layer "F.Fab")
		)
		(pad "1" smd circle
			(at 0 0 90)
			(size 0.8128 0.8128)
			(layers "F.Cu" "F.Mask" "F.Paste")
			(net "TP_COMP_A_NCSI_RCLK")
		)
	)
	(footprint ""
		(layer "F.Cu")
		(at 343.235534 -294.424862 180)
		(property "Reference" "R280"
			(at 0 0 180)
			(layer "F.SilkS")
			(hide yes)
			(effects
				(font
					(size 1.27 1.27)
				)
			)
		)
		(property "Value" "130R3F-GP"
			(at -0.0254 -2.5146 180)
			(unlocked yes)
			(layer "F.Fab")
			(hide yes)
			(effects
				(font
					(size 1.016 1.016)
					(thickness 0.1524)
				)
			)
		)
		(property "Device Type" "R603H22"
			(at -0.0254 -4.0386 180)
			(unlocked yes)
			(layer "F.Fab")
			(hide yes)
			(effects
				(font
					(size 1.016 1.016)
					(thickness 0.1524)
				)
			)
		)
		(duplicate_pad_numbers_are_jumpers no)
		(fp_line
			(start 0.2032 0)
			(end 0.4826 0)
			(stroke
				(width 0.2032)
				(type default)
			)
			(layer "F.SilkS")
		)
		(fp_line
			(start -0.4826 0)
			(end -0.2032 0)
			(stroke
				(width 0.2032)
				(type default)
			)
			(layer "F.SilkS")
		)
		(fp_rect
			(start -0.5842 1.3335)
			(end 0.5842 -1.3335)
			(stroke
				(width 0)
				(type default)
			)
			(fill no)
			(layer "F.CrtYd")
		)
		(fp_rect
			(start -0.5842 1.3335)
			(end 0.5842 -1.3335)
			(stroke
				(width 0)
				(type default)
			)
			(fill no)
			(layer "F.Fab")
		)
		(pad "1" smd custom
			(at 0 -0.762 180)
			(size 0.2159 0.2159)
			(layers "F.Cu" "F.Mask" "F.Paste")
			(net "P5V_B")
			(options
				(clearance outline)
				(anchor circle)
			)
			(primitives
				(gr_poly
					(pts
						(arc
							(start -0.3302 -0.4318)
							(mid -0.402042 -0.402042)
							(end -0.4318 -0.3302)
						)
						(arc
							(start -0.4318 0.3302)
							(mid -0.402042 0.402042)
							(end -0.3302 0.4318)
						)
						(arc
							(start 0.3302 0.4318)
							(mid 0.402042 0.402042)
							(end 0.4318 0.3302)
						)
						(arc
							(start 0.4318 -0.3302)
							(mid 0.402042 -0.402042)
							(end 0.3302 -0.4318)
						)
					)
					(width 0)
					(fill yes)
				)
			)
		)
		(pad "2" smd custom
			(at 0 0.762 180)
			(size 0.2159 0.2159)
			(layers "F.Cu" "F.Mask" "F.Paste")
			(net "FLT_HDD31")
			(options
				(clearance outline)
				(anchor circle)
			)
			(primitives
				(gr_poly
					(pts
						(arc
							(start -0.3302 -0.4318)
							(mid -0.402042 -0.402042)
							(end -0.4318 -0.3302)
						)
						(arc
							(start -0.4318 0.3302)
							(mid -0.402042 0.402042)
							(end -0.3302 0.4318)
						)
						(arc
							(start 0.3302 0.4318)
							(mid 0.402042 0.402042)
							(end 0.4318 0.3302)
						)
						(arc
							(start 0.4318 -0.3302)
							(mid 0.402042 -0.402042)
							(end 0.3302 -0.4318)
						)
					)
					(width 0)
					(fill yes)
				)
			)
		)
	)
)
